(kicad_pcb
	(version 20260206)
	(generator "pcbnew")
	(generator_version "10.0")
	(general
		(thickness 1.6)
		(legacy_teardrops no)
	)
	(paper "A4")
	(title_block
		(title "04192023_DAF0TMB3IC0_F0TG_MB_C_brd_V02_OCP.brd")
		(comment 1 "Grand Teton / footprint 3955 of 8354 (U25), pads 4449-4557 of 6102")
	)
	(layers
		(0 "F.Cu" signal "TOP")
		(4 "In1.Cu" signal "GND")
		(6 "In2.Cu" signal "IN1")
		(8 "In3.Cu" signal "GND1")
		(10 "In4.Cu" signal "IN2")
		(12 "In5.Cu" signal "GND2")
		(14 "In6.Cu" signal "IN3")
		(16 "In7.Cu" signal "GND3")
		(18 "In8.Cu" signal "VCC")
		(20 "In9.Cu" signal "VCC1")
		(22 "In10.Cu" signal "GND4")
		(24 "In11.Cu" signal "IN4")
		(26 "In12.Cu" signal "GND5")
		(28 "In13.Cu" signal "IN5")
		(30 "In14.Cu" signal "GND6")
		(32 "In15.Cu" signal "IN6")
		(34 "In16.Cu" signal "GND7")
		(2 "B.Cu" signal "BOTTOM")
		(9 "F.Adhes" user "F.Adhesive")
		(11 "B.Adhes" user "B.Adhesive")
		(13 "F.Paste" user "Package Geometry/Pastemask Top")
		(15 "B.Paste" user "Package Geometry/Pastemask Bottom")
		(5 "F.SilkS" user "Ref Des/Silkscreen Top")
		(7 "B.SilkS" user "Ref Des/Silkscreen Bottom")
		(1 "F.Mask" user "Board Geometry/Soldermask Top")
		(3 "B.Mask" user "Board Geometry/Soldermask Bottom")
		(17 "Dwgs.User" user "User.Drawings")
		(19 "Cmts.User" user "User.Comments")
		(21 "Eco1.User" user "User.Eco1")
		(23 "Eco2.User" user "User.Eco2")
		(25 "Edge.Cuts" user "Board Geometry/Outline")
		(27 "Margin" user)
		(31 "F.CrtYd" user "Package Geometry/Place Bound Top")
		(29 "B.CrtYd" user "Package Geometry/Place Bound Bottom")
		(35 "F.Fab" user "Ref Des/Assembly Top")
		(33 "B.Fab" user "Ref Des/Assembly Bottom")
	)
	(footprint ""
		(layer "F.Cu")
		(at 359.867962 -258.880102 180)
		(property "Reference" "U25"
			(at -45.78477 -62.086744 0)
			(unlocked yes)
			(layer "F.SilkS")
			(effects
				(font
					(size 0.7874 0.5842)
					(thickness 0.1524)
				)
			)
		)
		(property "Value" ""
			(at 0 0 180)
			(layer "F.Fab")
			(effects
				(font
					(size 1.27 1.27)
				)
			)
		)
		(duplicate_pad_numbers_are_jumpers no)
		(pad "DB59" smd circle
			(at 19.590004 31.139892 180)
			(size 0.450088 0.450088)
			(layers "F.Cu" "F.Mask" "F.Paste")
			(net "GND")
		)
		(pad "DB60" smd circle
			(at 20.530058 31.139892 180)
			(size 0.450088 0.450088)
			(layers "F.Cu" "F.Mask" "F.Paste")
			(net "M_D_CPU0_SB_DQS_DP<3>")
		)
		(pad "DB61" smd circle
			(at 21.470112 31.139892 180)
			(size 0.450088 0.450088)
			(layers "F.Cu" "F.Mask" "F.Paste")
			(net "GND")
		)
		(pad "DB62" smd circle
			(at 22.409912 31.139892 180)
			(size 0.450088 0.450088)
			(layers "F.Cu" "F.Mask" "F.Paste")
			(net "M_B_CPU0_SB_DQ<27>")
		)
		(pad "DB63" smd circle
			(at 23.349966 31.139892 180)
			(size 0.450088 0.450088)
			(layers "F.Cu" "F.Mask" "F.Paste")
			(net "M_B_CPU0_SB_DQS_DP<3>")
		)
		(pad "DB64" smd circle
			(at 24.29002 31.139892 180)
			(size 0.450088 0.450088)
			(layers "F.Cu" "F.Mask" "F.Paste")
			(net "PVDDIO_P0")
		)
		(pad "DB65" smd circle
			(at 25.230074 31.139892 180)
			(size 0.450088 0.450088)
			(layers "F.Cu" "F.Mask" "F.Paste")
			(net "M_F_CPU0_SB_DQ<27>")
		)
		(pad "DB66" smd circle
			(at 26.170128 31.139892 180)
			(size 0.450088 0.450088)
			(layers "F.Cu" "F.Mask" "F.Paste")
			(net "GND")
		)
		(pad "DB67" smd circle
			(at 27.109928 31.139892 180)
			(size 0.450088 0.450088)
			(layers "F.Cu" "F.Mask" "F.Paste")
			(net "M_F_CPU0_SB_DQS_DP<3>")
		)
		(pad "DB68" smd circle
			(at 28.049982 31.139892 180)
			(size 0.450088 0.450088)
			(layers "F.Cu" "F.Mask" "F.Paste")
			(net "GND")
		)
		(pad "DB69" smd circle
			(at 28.990036 31.139892 180)
			(size 0.450088 0.450088)
			(layers "F.Cu" "F.Mask" "F.Paste")
			(net "M_E_CPU0_SB_DQ<27>")
		)
		(pad "DB70" smd circle
			(at 29.93009 31.139892 180)
			(size 0.450088 0.450088)
			(layers "F.Cu" "F.Mask" "F.Paste")
			(net "M_E_CPU0_SB_DQS_DP<3>")
		)
		(pad "DB71" smd circle
			(at 30.86989 31.139892 180)
			(size 0.450088 0.450088)
			(layers "F.Cu" "F.Mask" "F.Paste")
			(net "PVDDIO_P0")
		)
		(pad "DB72" smd circle
			(at 31.809944 31.139892 180)
			(size 0.450088 0.450088)
			(layers "F.Cu" "F.Mask" "F.Paste")
			(net "M_A_CPU0_SB_DQ<27>")
		)
		(pad "DB73" smd circle
			(at 32.749998 31.139892 180)
			(size 0.450088 0.450088)
			(layers "F.Cu" "F.Mask" "F.Paste")
			(net "GND")
		)
		(pad "DB74" smd circle
			(at 33.690052 31.139892 180)
			(size 0.450088 0.450088)
			(layers "F.Cu" "F.Mask" "F.Paste")
			(net "M_A_CPU0_SB_DQS_DP<3>")
		)
		(pad "DC1" smd circle
			(at -34.459926 31.949898 180)
			(size 0.450088 0.450088)
			(layers "F.Cu" "F.Mask" "F.Paste")
			(net "GND")
		)
		(pad "DC2" smd circle
			(at -33.519872 31.949898 180)
			(size 0.450088 0.450088)
			(layers "F.Cu" "F.Mask" "F.Paste")
			(net "M_G_CPU0_SB_DQS_DN<3>")
		)
		(pad "DC3" smd circle
			(at -32.580072 31.949898 180)
			(size 0.450088 0.450088)
			(layers "F.Cu" "F.Mask" "F.Paste")
			(net "M_G_CPU0_SB_DQS_DN<8>")
		)
		(pad "DC4" smd circle
			(at -31.640018 31.949898 180)
			(size 0.450088 0.450088)
			(layers "F.Cu" "F.Mask" "F.Paste")
			(net "GND")
		)
		(pad "DC5" smd circle
			(at -30.699964 31.949898 180)
			(size 0.450088 0.450088)
			(layers "F.Cu" "F.Mask" "F.Paste")
			(net "M_K_CPU0_SB_DQS_DN<3>")
		)
		(pad "DC6" smd circle
			(at -29.75991 31.949898 180)
			(size 0.450088 0.450088)
			(layers "F.Cu" "F.Mask" "F.Paste")
			(net "GND")
		)
		(pad "DC7" smd circle
			(at -28.82011 31.949898 180)
			(size 0.450088 0.450088)
			(layers "F.Cu" "F.Mask" "F.Paste")
			(net "M_K_CPU0_SB_DQS_DN<8>")
		)
		(pad "DC8" smd circle
			(at -27.880056 31.949898 180)
			(size 0.450088 0.450088)
			(layers "F.Cu" "F.Mask" "F.Paste")
			(net "GND")
		)
		(pad "DC9" smd circle
			(at -26.940002 31.949898 180)
			(size 0.450088 0.450088)
			(layers "F.Cu" "F.Mask" "F.Paste")
			(net "M_L_CPU0_SB_DQS_DN<3>")
		)
		(pad "DC10" smd circle
			(at -25.999948 31.949898 180)
			(size 0.450088 0.450088)
			(layers "F.Cu" "F.Mask" "F.Paste")
			(net "M_L_CPU0_SB_DQS_DN<8>")
		)
		(pad "DC11" smd circle
			(at -25.059894 31.949898 180)
			(size 0.450088 0.450088)
			(layers "F.Cu" "F.Mask" "F.Paste")
			(net "GND")
		)
		(pad "DC12" smd circle
			(at -24.120094 31.949898 180)
			(size 0.450088 0.450088)
			(layers "F.Cu" "F.Mask" "F.Paste")
			(net "M_H_CPU0_SB_DQS_DN<3>")
		)
		(pad "DC13" smd circle
			(at -23.18004 31.949898 180)
			(size 0.450088 0.450088)
			(layers "F.Cu" "F.Mask" "F.Paste")
			(net "GND")
		)
		(pad "DC14" smd circle
			(at -22.239986 31.949898 180)
			(size 0.450088 0.450088)
			(layers "F.Cu" "F.Mask" "F.Paste")
			(net "M_H_CPU0_SB_DQS_DN<8>")
		)
		(pad "DC15" smd circle
			(at -21.299932 31.949898 180)
			(size 0.450088 0.450088)
			(layers "F.Cu" "F.Mask" "F.Paste")
			(net "GND")
		)
		(pad "DC16" smd circle
			(at -20.359878 31.949898 180)
			(size 0.450088 0.450088)
			(layers "F.Cu" "F.Mask" "F.Paste")
			(net "M_J_CPU0_SB_DQS_DN<3>")
		)
		(pad "DC17" smd circle
			(at -19.420078 31.949898 180)
			(size 0.450088 0.450088)
			(layers "F.Cu" "F.Mask" "F.Paste")
			(net "M_J_CPU0_SB_DQS_DN<8>")
		)
		(pad "DC18" smd circle
			(at -18.480024 31.949898 180)
			(size 0.450088 0.450088)
			(layers "F.Cu" "F.Mask" "F.Paste")
			(net "GND")
		)
		(pad "DC19" smd circle
			(at -17.53997 31.949898 180)
			(size 0.450088 0.450088)
			(layers "F.Cu" "F.Mask" "F.Paste")
			(net "M_I_CPU0_SB_DQS_DN<3>")
		)
		(pad "DC20" smd circle
			(at -16.599916 31.949898 180)
			(size 0.450088 0.450088)
			(layers "F.Cu" "F.Mask" "F.Paste")
			(net "GND")
		)
		(pad "DC21" smd circle
			(at -15.660116 31.949898 180)
			(size 0.450088 0.450088)
			(layers "F.Cu" "F.Mask" "F.Paste")
			(net "M_I_CPU0_SB_DQS_DN<8>")
		)
		(pad "DC22" smd circle
			(at -14.720062 31.949898 180)
			(size 0.450088 0.450088)
			(layers "F.Cu" "F.Mask" "F.Paste")
			(net "GND")
		)
		(pad "DC23" smd circle
			(at -13.780008 31.949898 180)
			(size 0.450088 0.450088)
			(layers "F.Cu" "F.Mask" "F.Paste")
			(net "P5E_CPU0_P3_RX_DP<13>")
		)
		(pad "DC24" smd circle
			(at -12.839954 31.949898 180)
			(size 0.450088 0.450088)
			(layers "F.Cu" "F.Mask" "F.Paste")
			(net "P5E_CPU0_P3_RX_DN<13>")
		)
		(pad "DC25" smd circle
			(at -11.8999 31.949898 180)
			(size 0.450088 0.450088)
			(layers "F.Cu" "F.Mask" "F.Paste")
			(net "GND")
		)
		(pad "DC26" smd circle
			(at -10.9601 31.949898 180)
			(size 0.450088 0.450088)
			(layers "F.Cu" "F.Mask" "F.Paste")
			(net "P5E_CPU0_P3_RX_DP<10>")
		)
		(pad "DC27" smd circle
			(at -10.020046 31.949898 180)
			(size 0.450088 0.450088)
			(layers "F.Cu" "F.Mask" "F.Paste")
			(net "P5E_CPU0_P3_RX_DN<10>")
		)
		(pad "DC28" smd circle
			(at -9.079992 31.949898 180)
			(size 0.450088 0.450088)
			(layers "F.Cu" "F.Mask" "F.Paste")
			(net "GND")
		)
		(pad "DC29" smd circle
			(at -8.139938 31.949898 180)
			(size 0.450088 0.450088)
			(layers "F.Cu" "F.Mask" "F.Paste")
			(net "P5E_CPU0_P3_RX_DP<7>")
		)
		(pad "DC30" smd circle
			(at -7.199884 31.949898 180)
			(size 0.450088 0.450088)
			(layers "F.Cu" "F.Mask" "F.Paste")
			(net "P5E_CPU0_P3_RX_DN<7>")
		)
		(pad "DC31" smd circle
			(at -6.260084 31.949898 180)
			(size 0.450088 0.450088)
			(layers "F.Cu" "F.Mask" "F.Paste")
			(net "GND")
		)
		(pad "DC32" smd circle
			(at -5.32003 31.949898 180)
			(size 0.450088 0.450088)
			(layers "F.Cu" "F.Mask" "F.Paste")
			(net "P5E_CPU0_P3_RX_DP<4>")
		)
		(pad "DC33" smd circle
			(at -4.379976 31.949898 180)
			(size 0.450088 0.450088)
			(layers "F.Cu" "F.Mask" "F.Paste")
			(net "P5E_CPU0_P3_RX_DN<4>")
		)
		(pad "DC34" smd circle
			(at -3.439922 31.949898 180)
			(size 0.450088 0.450088)
			(layers "F.Cu" "F.Mask" "F.Paste")
			(net "GND")
		)
		(pad "DC35" smd circle
			(at -2.500122 31.949898 180)
			(size 0.450088 0.450088)
			(layers "F.Cu" "F.Mask" "F.Paste")
			(net "PVDDCR_CPU1_P0")
		)
		(pad "DC36" smd circle
			(at -1.560068 31.949898 180)
			(size 0.450088 0.450088)
			(layers "F.Cu" "F.Mask" "F.Paste")
			(net "PVDDCR_CPU1_P0")
		)
		(pad "DC40" smd circle
			(at 1.260094 31.949898 180)
			(size 0.450088 0.450088)
			(layers "F.Cu" "F.Mask" "F.Paste")
			(net "PVDDCR_CPU1_P0")
		)
		(pad "DC41" smd circle
			(at 2.199894 31.949898 180)
			(size 0.450088 0.450088)
			(layers "F.Cu" "F.Mask" "F.Paste")
			(net "PVDDCR_CPU1_P0")
		)
		(pad "DC42" smd circle
			(at 3.139948 31.949898 180)
			(size 0.450088 0.450088)
			(layers "F.Cu" "F.Mask" "F.Paste")
			(net "GND")
		)
		(pad "DC43" smd circle
			(at 4.080002 31.949898 180)
			(size 0.450088 0.450088)
			(layers "F.Cu" "F.Mask" "F.Paste")
			(net "P5E_CPU0_P1_TX_DN<11>")
		)
		(pad "DC44" smd circle
			(at 5.020056 31.949898 180)
			(size 0.450088 0.450088)
			(layers "F.Cu" "F.Mask" "F.Paste")
			(net "P5E_CPU0_P1_TX_DP<11>")
		)
		(pad "DC45" smd circle
			(at 5.96011 31.949898 180)
			(size 0.450088 0.450088)
			(layers "F.Cu" "F.Mask" "F.Paste")
			(net "GND")
		)
		(pad "DC46" smd circle
			(at 6.89991 31.949898 180)
			(size 0.450088 0.450088)
			(layers "F.Cu" "F.Mask" "F.Paste")
			(net "P5E_CPU0_P1_TX_DN<8>")
		)
		(pad "DC47" smd circle
			(at 7.839964 31.949898 180)
			(size 0.450088 0.450088)
			(layers "F.Cu" "F.Mask" "F.Paste")
			(net "P5E_CPU0_P1_TX_DP<8>")
		)
		(pad "DC48" smd circle
			(at 8.780018 31.949898 180)
			(size 0.450088 0.450088)
			(layers "F.Cu" "F.Mask" "F.Paste")
			(net "GND")
		)
		(pad "DC49" smd circle
			(at 9.720072 31.949898 180)
			(size 0.450088 0.450088)
			(layers "F.Cu" "F.Mask" "F.Paste")
			(net "P5E_CPU0_P1_TX_DN<5>")
		)
		(pad "DC50" smd circle
			(at 10.659872 31.949898 180)
			(size 0.450088 0.450088)
			(layers "F.Cu" "F.Mask" "F.Paste")
			(net "P5E_CPU0_P1_TX_DP<5>")
		)
		(pad "DC51" smd circle
			(at 11.599926 31.949898 180)
			(size 0.450088 0.450088)
			(layers "F.Cu" "F.Mask" "F.Paste")
			(net "GND")
		)
		(pad "DC52" smd circle
			(at 12.53998 31.949898 180)
			(size 0.450088 0.450088)
			(layers "F.Cu" "F.Mask" "F.Paste")
			(net "P5E_CPU0_P1_TX_DN<2>")
		)
		(pad "DC53" smd circle
			(at 13.480034 31.949898 180)
			(size 0.450088 0.450088)
			(layers "F.Cu" "F.Mask" "F.Paste")
			(net "P5E_CPU0_P1_TX_DP<2>")
		)
		(pad "DC54" smd circle
			(at 14.420088 31.949898 180)
			(size 0.450088 0.450088)
			(layers "F.Cu" "F.Mask" "F.Paste")
			(net "GND")
		)
		(pad "DC55" smd circle
			(at 15.359888 31.949898 180)
			(size 0.450088 0.450088)
			(layers "F.Cu" "F.Mask" "F.Paste")
			(net "M_C_CPU0_SB_DQS_DN<8>")
		)
		(pad "DC56" smd circle
			(at 16.299942 31.949898 180)
			(size 0.450088 0.450088)
			(layers "F.Cu" "F.Mask" "F.Paste")
			(net "GND")
		)
		(pad "DC57" smd circle
			(at 17.239996 31.949898 180)
			(size 0.450088 0.450088)
			(layers "F.Cu" "F.Mask" "F.Paste")
			(net "M_C_CPU0_SB_DQS_DN<3>")
		)
		(pad "DC58" smd circle
			(at 18.18005 31.949898 180)
			(size 0.450088 0.450088)
			(layers "F.Cu" "F.Mask" "F.Paste")
			(net "GND")
		)
		(pad "DC59" smd circle
			(at 19.120104 31.949898 180)
			(size 0.450088 0.450088)
			(layers "F.Cu" "F.Mask" "F.Paste")
			(net "M_D_CPU0_SB_DQS_DN<8>")
		)
		(pad "DC60" smd circle
			(at 20.059904 31.949898 180)
			(size 0.450088 0.450088)
			(layers "F.Cu" "F.Mask" "F.Paste")
			(net "M_D_CPU0_SB_DQS_DN<3>")
		)
		(pad "DC61" smd circle
			(at 20.999958 31.949898 180)
			(size 0.450088 0.450088)
			(layers "F.Cu" "F.Mask" "F.Paste")
			(net "GND")
		)
		(pad "DC62" smd circle
			(at 21.940012 31.949898 180)
			(size 0.450088 0.450088)
			(layers "F.Cu" "F.Mask" "F.Paste")
			(net "M_B_CPU0_SB_DQS_DN<8>")
		)
		(pad "DC63" smd circle
			(at 22.880066 31.949898 180)
			(size 0.450088 0.450088)
			(layers "F.Cu" "F.Mask" "F.Paste")
			(net "GND")
		)
		(pad "DC64" smd circle
			(at 23.82012 31.949898 180)
			(size 0.450088 0.450088)
			(layers "F.Cu" "F.Mask" "F.Paste")
			(net "M_B_CPU0_SB_DQS_DN<3>")
		)
		(pad "DC65" smd circle
			(at 24.75992 31.949898 180)
			(size 0.450088 0.450088)
			(layers "F.Cu" "F.Mask" "F.Paste")
			(net "GND")
		)
		(pad "DC66" smd circle
			(at 25.699974 31.949898 180)
			(size 0.450088 0.450088)
			(layers "F.Cu" "F.Mask" "F.Paste")
			(net "M_F_CPU0_SB_DQS_DN<8>")
		)
		(pad "DC67" smd circle
			(at 26.640028 31.949898 180)
			(size 0.450088 0.450088)
			(layers "F.Cu" "F.Mask" "F.Paste")
			(net "M_F_CPU0_SB_DQS_DN<3>")
		)
		(pad "DC68" smd circle
			(at 27.580082 31.949898 180)
			(size 0.450088 0.450088)
			(layers "F.Cu" "F.Mask" "F.Paste")
			(net "GND")
		)
		(pad "DC69" smd circle
			(at 28.519882 31.949898 180)
			(size 0.450088 0.450088)
			(layers "F.Cu" "F.Mask" "F.Paste")
			(net "M_E_CPU0_SB_DQS_DN<8>")
		)
		(pad "DC70" smd circle
			(at 29.459936 31.949898 180)
			(size 0.450088 0.450088)
			(layers "F.Cu" "F.Mask" "F.Paste")
			(net "GND")
		)
		(pad "DC71" smd circle
			(at 30.39999 31.949898 180)
			(size 0.450088 0.450088)
			(layers "F.Cu" "F.Mask" "F.Paste")
			(net "M_E_CPU0_SB_DQS_DN<3>")
		)
		(pad "DC72" smd circle
			(at 31.340044 31.949898 180)
			(size 0.450088 0.450088)
			(layers "F.Cu" "F.Mask" "F.Paste")
			(net "GND")
		)
		(pad "DC73" smd circle
			(at 32.280098 31.949898 180)
			(size 0.450088 0.450088)
			(layers "F.Cu" "F.Mask" "F.Paste")
			(net "M_A_CPU0_SB_DQS_DN<8>")
		)
		(pad "DC74" smd circle
			(at 33.219898 31.949898 180)
			(size 0.450088 0.450088)
			(layers "F.Cu" "F.Mask" "F.Paste")
			(net "M_A_CPU0_SB_DQS_DN<3>")
		)
		(pad "DC75" smd circle
			(at 34.159952 31.949898 180)
			(size 0.450088 0.450088)
			(layers "F.Cu" "F.Mask" "F.Paste")
			(net "GND")
		)
		(pad "DD2" smd circle
			(at -33.990026 32.759904 180)
			(size 0.450088 0.450088)
			(layers "F.Cu" "F.Mask" "F.Paste")
			(net "M_G_CPU0_SB_DQ<28>")
		)
		(pad "DD3" smd circle
			(at -33.049972 32.759904 180)
			(size 0.450088 0.450088)
			(layers "F.Cu" "F.Mask" "F.Paste")
			(net "GND")
		)
		(pad "DD4" smd circle
			(at -32.109918 32.759904 180)
			(size 0.450088 0.450088)
			(layers "F.Cu" "F.Mask" "F.Paste")
			(net "M_G_CPU0_SB_DQS_DP<8>")
		)
		(pad "DD5" smd circle
			(at -31.170118 32.759904 180)
			(size 0.450088 0.450088)
			(layers "F.Cu" "F.Mask" "F.Paste")
			(net "GND")
		)
		(pad "DD6" smd circle
			(at -30.230064 32.759904 180)
			(size 0.450088 0.450088)
			(layers "F.Cu" "F.Mask" "F.Paste")
			(net "M_K_CPU0_SB_DQ<28>")
		)
		(pad "DD7" smd circle
			(at -29.29001 32.759904 180)
			(size 0.450088 0.450088)
			(layers "F.Cu" "F.Mask" "F.Paste")
			(net "M_K_CPU0_SB_DQS_DP<8>")
		)
		(pad "DD8" smd circle
			(at -28.349956 32.759904 180)
			(size 0.450088 0.450088)
			(layers "F.Cu" "F.Mask" "F.Paste")
			(net "GND")
		)
		(pad "DD9" smd circle
			(at -27.409902 32.759904 180)
			(size 0.450088 0.450088)
			(layers "F.Cu" "F.Mask" "F.Paste")
			(net "M_L_CPU0_SB_DQ<28>")
		)
		(pad "DD10" smd circle
			(at -26.470102 32.759904 180)
			(size 0.450088 0.450088)
			(layers "F.Cu" "F.Mask" "F.Paste")
			(net "GND")
		)
		(pad "DD11" smd circle
			(at -25.530048 32.759904 180)
			(size 0.450088 0.450088)
			(layers "F.Cu" "F.Mask" "F.Paste")
			(net "M_L_CPU0_SB_DQS_DP<8>")
		)
		(pad "DD12" smd circle
			(at -24.589994 32.759904 180)
			(size 0.450088 0.450088)
			(layers "F.Cu" "F.Mask" "F.Paste")
			(net "GND")
		)
		(pad "DD13" smd circle
			(at -23.64994 32.759904 180)
			(size 0.450088 0.450088)
			(layers "F.Cu" "F.Mask" "F.Paste")
			(net "M_H_CPU0_SB_DQ<28>")
		)
		(pad "DD14" smd circle
			(at -22.709886 32.759904 180)
			(size 0.450088 0.450088)
			(layers "F.Cu" "F.Mask" "F.Paste")
			(net "M_H_CPU0_SB_DQS_DP<8>")
		)
		(pad "DD15" smd circle
			(at -21.770086 32.759904 180)
			(size 0.450088 0.450088)
			(layers "F.Cu" "F.Mask" "F.Paste")
			(net "GND")
		)
		(pad "DD16" smd circle
			(at -20.830032 32.759904 180)
			(size 0.450088 0.450088)
			(layers "F.Cu" "F.Mask" "F.Paste")
			(net "M_J_CPU0_SB_DQ<28>")
		)
		(pad "DD17" smd circle
			(at -19.889978 32.759904 180)
			(size 0.450088 0.450088)
			(layers "F.Cu" "F.Mask" "F.Paste")
			(net "GND")
		)
		(pad "DD18" smd circle
			(at -18.949924 32.759904 180)
			(size 0.450088 0.450088)
			(layers "F.Cu" "F.Mask" "F.Paste")
			(net "M_J_CPU0_SB_DQS_DP<8>")
		)
		(pad "DD19" smd circle
			(at -18.010124 32.759904 180)
			(size 0.450088 0.450088)
			(layers "F.Cu" "F.Mask" "F.Paste")
			(net "GND")
		)
		(pad "DD20" smd circle
			(at -17.07007 32.759904 180)
			(size 0.450088 0.450088)
			(layers "F.Cu" "F.Mask" "F.Paste")
			(net "M_I_CPU0_SB_DQ<28>")
		)
		(pad "DD21" smd circle
			(at -16.130016 32.759904 180)
			(size 0.450088 0.450088)
			(layers "F.Cu" "F.Mask" "F.Paste")
			(net "M_I_CPU0_SB_DQS_DP<8>")
		)
		(pad "DD22" smd circle
			(at -15.189962 32.759904 180)
			(size 0.450088 0.450088)
			(layers "F.Cu" "F.Mask" "F.Paste")
			(net "PVDDCR_CPU1_P0")
		)
	)
)
